# netlist discovery v1 revB.xlsx — Feuille1_2 (netlist-table)
| P  CODE 00 |  |  |  |  |
| P  UNITS CUST 0 |  |  |  |  |
| P  DIM   N |  |  |  |  |
| 367N/C | J2 |  | D1193UA00X+011851Y+021062X1575Y0000R090 | S0 |
| 367N/C | J2 |  | D1193UA00X+011851Y+014055X1575Y0000R090 | S0 |
| 317+12V | J2 | -1 | D0728PA00X+010197Y+015905X0984Y0000R090 | S0 |
| 317+12V | J2 | -2 | D0728PA00X+010197Y+017558X0984Y0000R090 | S0 |
| 317+12V | J2 | -3 | D0728PA00X+010197Y+019212X0984Y0000R090 | S0 |
| 317GND | J2 | -4 | D0728PA00X+011851Y+015905X0984Y0000R090 | S0 |
| 317GND | J2 | -5 | D0728PA00X+011851Y+017558X0984Y0000R090 | S0 |
| 317GND | J2 | -6 | D0728PA00X+011851Y+019212X0984Y0000R090 | S0 |
| 317GND | J4 | -6 | D0728PA00X+002323Y+015905X0984Y0000R270 | S0 |
| 317GND | J4 | -5 | D0728PA00X+002323Y+017558X0984Y0000R270 | S0 |
| 317GND | J4 | -4 | D0728PA00X+002323Y+019212X0984Y0000R270 | S0 |
| 317+12V | J4 | -3 | D0728PA00X+003977Y+015905X0984Y0000R270 | S0 |
| 317+12V | J4 | -2 | D0728PA00X+003977Y+017558X0984Y0000R270 | S0 |
| 317+12V | J4 | -1 | D0728PA00X+003977Y+019212X0984Y0000R270 | S0 |
| 367N/C | J4 |  | D1193UA00X+002323Y+021062X1575Y0000R270 | S0 |
| 367N/C | J4 |  | D1193UA00X+002323Y+014055X1575Y0000R270 | S0 |
| 367N/C | J5 |  | D1193UA00X+002323Y+002703X1575Y0000R270 | S0 |
| 367N/C | J5 |  | D1193UA00X+002323Y+009711X1575Y0000R270 | S0 |
| 317+12V | J5 | -1 | D0728PA00X+003977Y+007861X0984Y0000R270 | S0 |
| 317+12V | J5 | -2 | D0728PA00X+003977Y+006207X0984Y0000R270 | S0 |
| 317+12V | J5 | -3 | D0728PA00X+003977Y+004553X0984Y0000R270 | S0 |
| 317GND | J5 | -4 | D0728PA00X+002323Y+007861X0984Y0000R270 | S0 |
| 317GND | J5 | -5 | D0728PA00X+002323Y+006207X0984Y0000R270 | S0 |
| 317GND | J5 | -6 | D0728PA00X+002323Y+004553X0984Y0000R270 | S0 |
| 317GND | J6 | -6 | D0728PA00X+011851Y+007861X0984Y0000R090 | S0 |
| 317GND | J6 | -5 | D0728PA00X+011851Y+006207X0984Y0000R090 | S0 |
| 317GND | J6 | -4 | D0728PA00X+011851Y+004553X0984Y0000R090 | S0 |
| 317+12V | J6 | -3 | D0728PA00X+010197Y+007861X0984Y0000R090 | S0 |
| 317+12V | J6 | -2 | D0728PA00X+010197Y+006207X0984Y0000R090 | S0 |
| 317+12V | J6 | -1 | D0728PA00X+010197Y+004553X0984Y0000R090 | S0 |
| 367N/C | J6 |  | D1193UA00X+011851Y+002703X1575Y0000R090 | S0 |
| 367N/C | J6 |  | D1193UA00X+011851Y+009711X1575Y0000R090 | S0 |
| 317+12V | J1 | -8 | D0709PA00X+002402Y+026141X0984Y0000R270 | S0 |
| 317+12V | J1 | -7 | D0709PA00X+002402Y+027795X0984Y0000R270 | S0 |
| 317+12V | J1 | -6 | D0709PA00X+002402Y+029448X0984Y0000R270 | S0 |
| 317+12V | J1 | -5 | D0709PA00X+002402Y+031102X0984Y0000R270 | S0 |
| 317GND | J1 | -4 | D0709PA00X+004056Y+026141X0984Y0000R270 | S0 |
| 317GND | J1 | -3 | D0709PA00X+004056Y+027795X0984Y0000R270 | S0 |
| 317GND | J1 | -2 | D0709PA00X+004056Y+029448X0984Y0000R270 | S0 |
| 317GND | J1 | -1 | D0709PA00X+004056Y+031102X0984Y0000R270 | S0 |
| 367N/C | J1 |  | D1193UA00X+002323Y+032952X1575Y0000R270 | S0 |
| 367N/C | J1 |  | D1193UA00X+002323Y+024291X1575Y0000R270 | S0 |
| 367N/C | J3 |  | D1193UA00X+011851Y+032952X1575Y0000R090 | S0 |
| 367N/C | J3 |  | D1193UA00X+011851Y+024291X1575Y0000R090 | S0 |
| 317GND | J3 | -1 | D0709PA00X+010119Y+026141X0984Y0000R090 | S0 |
| 317GND | J3 | -2 | D0709PA00X+010119Y+027795X0984Y0000R090 | S0 |
| 317GND | J3 | -3 | D0709PA00X+010119Y+029448X0984Y0000R090 | S0 |
| 317GND | J3 | -4 | D0709PA00X+010119Y+031102X0984Y0000R090 | S0 |
| 317+12V | J3 | -5 | D0709PA00X+011772Y+026141X0984Y0000R090 | S0 |
| 317+12V | J3 | -6 | D0709PA00X+011772Y+027795X0984Y0000R090 | S0 |
| 317+12V | J3 | -7 | D0709PA00X+011772Y+029448X0984Y0000R090 | S0 |
| 317+12V | J3 | -8 | D0709PA00X+011772Y+031102X0984Y0000R090 | S0 |
| 317GND | W1 | -1 | D1575PA00X+055119Y-000001X1969Y0000R000 | S0 |
| 317GND | W2 | -1 | D1575PA00X+000001Y+035432X1969Y0000R000 | S0 |
| 317GND | W3 | -1 | D1575PA00X+055119Y+035432X1969Y0000R000 | S0 |
| 317GND | W4 | -1 | D1575PA00X+000001Y-000001X1969Y0000R000 | S0 |
| 317+12V | W5 | -1 | D2244PA00X+021654Y+030708X5906Y0000R000 | S0 |
| 317+12V | W6 | -1 | D2244PA00X+021654Y+021850X5906Y0000R000 | S0 |
| 317+12V | W7 | -1 | D2244PA00X+021654Y+012992X5906Y0000R000 | S0 |
| 317+12V | W8 | -1 | D2244PA00X+021654Y+004133X5906Y0000R000 | S0 |
| 317GND | W9 | -1 | D2244PA00X+045276Y+031791X5906Y0000R000 | S0 |
| 317GND | W10 | -1 | D2244PA00X+045276Y+022932X5906Y0000R000 | S0 |
| 317GND | W11 | -1 | D2244PA00X+045276Y+005216X5906Y0000R000 | S0 |
| 317GND | W12 | -1 | D2244PA00X+045276Y+014074X5906Y0000R000 | S0 |
| 999 |  |  |  |  |
